# BASEBOARD_FAB2 (Tioga Pass) — schematic netlist excerpt (pin names and nets, part order shuffled) for the footprints in the layout excerpt that follows; sources: Cadence DE-HDL packaged netlist, KiCad conversion of Wiwynn_Tioga_Pass_MB.brd

R6W50  RES  4.75K 1% CHIP  pkg 0402  page 176 : A = P3V3_STBY ; B = SPA_MID_DBG2_RX
C5P13  CAP  100UF 4V 20% X5R  pkg 0805  page 42 : A = PVCCMCP_CPU0 ; B = GND
C2R10  CAP  0.22UF 16V 10% X7R  pkg 0402  page 106 : A = P3E_CPU0_PE3_OCP_TXP<7> ; B = P3E_OCP_CPU0_PE3_C_TXP<7>

(kicad_pcb
	(version 20260206)
	(generator "pcbnew")
	(generator_version "10.0")
	(general
		(thickness 1.6)
		(legacy_teardrops no)
	)
	(paper "A4")
	(title_block
		(title "Wiwynn_Tioga_Pass_MB.brd")
		(comment 1 "Tioga Pass / footprints 3750-3752 of 4770")
	)
	(layers
		(0 "F.Cu" signal "TOP")
		(4 "In1.Cu" signal "L2GND")
		(6 "In2.Cu" signal "L3")
		(8 "In3.Cu" signal "L4GND")
		(10 "In4.Cu" signal "L5")
		(12 "In5.Cu" signal "L6GND")
		(14 "In6.Cu" signal "L7VCC")
		(16 "In7.Cu" signal "L8VCC")
		(18 "In8.Cu" signal "L9GND")
		(20 "In9.Cu" signal "L10")
		(22 "In10.Cu" signal "L11GND")
		(24 "In11.Cu" signal "L12")
		(26 "In12.Cu" signal "L13GND")
		(2 "B.Cu" signal "BOTTOM")
		(9 "F.Adhes" user "F.Adhesive")
		(11 "B.Adhes" user "B.Adhesive")
		(13 "F.Paste" user "Package Geometry/Pastemask Top")
		(15 "B.Paste" user "Package Geometry/Pastemask Bottom")
		(5 "F.SilkS" user "Ref Des/Silkscreen Top")
		(7 "B.SilkS" user "Ref Des/Silkscreen Bottom")
		(1 "F.Mask" user "Board Geometry/Soldermask Top")
		(3 "B.Mask" user "Board Geometry/Soldermask Bottom")
		(17 "Dwgs.User" user "User.Drawings")
		(19 "Cmts.User" user "User.Comments")
		(21 "Eco1.User" user "User.Eco1")
		(23 "Eco2.User" user "User.Eco2")
		(25 "Edge.Cuts" user "Board Geometry/Outline")
		(27 "Margin" user)
		(31 "F.CrtYd" user "Package Geometry/Place Bound Top")
		(29 "B.CrtYd" user "Package Geometry/Place Bound Bottom")
		(35 "F.Fab" user "Ref Des/Assembly Top")
		(33 "B.Fab" user "Ref Des/Assembly Bottom")
	)
	(footprint ""
		(layer "B.Cu")
		(at 491.41888 -132.1816 180)
		(property "Reference" "R6W50"
			(at 0.8382 -0.67818 180)
			(unlocked yes)
			(layer "B.SilkS")
			(effects
				(font
					(size 0.4064 0.254)
					(thickness 0.1524)
				)
				(justify left mirror)
			)
		)
		(property "Value" ""
			(at 0 0 0)
			(layer "B.Fab")
			(effects
				(font
					(size 1.27 1.27)
				)
				(justify mirror)
			)
		)
		(duplicate_pad_numbers_are_jumpers no)
		(fp_poly
			(pts
				(xy 0.2794 -0.1016) (xy -0.2794 -0.1016) (xy -0.2794 0.9906) (xy 0.2794 0.9906)
			)
			(stroke
				(width 0)
				(type default)
			)
			(fill no)
			(layer "B.CrtYd")
		)
		(fp_line
			(start 0.2794 0.9906)
			(end -0.2794 0.9906)
			(stroke
				(width 0.1)
				(type default)
			)
			(layer "B.Fab")
		)
		(fp_line
			(start 0.2794 -0.1016)
			(end 0.2794 0.9906)
			(stroke
				(width 0.1)
				(type default)
			)
			(layer "B.Fab")
		)
		(fp_line
			(start -0.2794 0.9906)
			(end -0.2794 -0.1016)
			(stroke
				(width 0.1)
				(type default)
			)
			(layer "B.Fab")
		)
		(fp_line
			(start -0.2794 -0.1016)
			(end 0.2794 -0.1016)
			(stroke
				(width 0.1)
				(type default)
			)
			(layer "B.Fab")
		)
		(pad "1" smd rect
			(at 0 0)
			(size 0.508 0.508)
			(layers "B.Cu" "B.Mask" "B.Paste")
			(net "P3V3_STBY")
		)
		(pad "2" smd rect
			(at 0 0.889)
			(size 0.508 0.508)
			(layers "B.Cu" "B.Mask" "B.Paste")
			(net "SPA_MID_DBG2_RX")
		)
		(zone
			(layer "B.Cu")
			(hatch none 0.5)
			(connect_pads
				(clearance 0)
			)
			(min_thickness 0.25)
			(keepout
				(tracks not_allowed)
				(vias allowed)
				(pads allowed)
				(copperpour not_allowed)
				(footprints allowed)
			)
			(placement
				(enabled no)
				(sheetname "")
			)
			(fill
				(thermal_gap 0.5)
				(thermal_bridge_width 0.5)
				(island_removal_mode 0)
			)
			(polygon
				(pts
					(xy 491.16488 -132.8166) (xy 491.67288 -132.8166) (xy 491.67288 -132.4356) (xy 491.16488 -132.4356)
				)
			)
		)
		(zone
			(layer "B.Cu")
			(hatch none 0.5)
			(connect_pads
				(clearance 0)
			)
			(min_thickness 0.25)
			(keepout
				(tracks allowed)
				(vias not_allowed)
				(pads allowed)
				(copperpour not_allowed)
				(footprints allowed)
			)
			(placement
				(enabled no)
				(sheetname "")
			)
			(fill
				(thermal_gap 0.5)
				(thermal_bridge_width 0.5)
				(island_removal_mode 0)
			)
			(polygon
				(pts
					(xy 491.16488 -132.4356) (xy 491.67288 -132.4356) (xy 491.67288 -132.8166) (xy 491.16488 -132.8166)
				)
			)
		)
	)
	(footprint ""
		(layer "B.Cu")
		(at 440.4614 -52.2986)
		(property "Reference" "C2R10"
			(at 0 0 0)
			(layer "B.SilkS")
			(hide yes)
			(effects
				(font
					(size 1.27 1.27)
				)
				(justify mirror)
			)
		)
		(property "Value" ""
			(at 0 0 0)
			(layer "B.Fab")
			(effects
				(font
					(size 1.27 1.27)
				)
				(justify mirror)
			)
		)
		(duplicate_pad_numbers_are_jumpers no)
		(fp_poly
			(pts
				(xy -0.3048 -0.1016) (xy -0.3048 0.9906) (xy 0.3048 0.9906) (xy 0.3048 -0.1016)
			)
			(stroke
				(width 0)
				(type default)
			)
			(fill no)
			(layer "B.CrtYd")
		)
		(fp_line
			(start -0.3048 -0.1016)
			(end 0.3048 -0.1016)
			(stroke
				(width 0.1)
				(type default)
			)
			(layer "B.Fab")
		)
		(fp_line
			(start -0.3048 0.9906)
			(end -0.3048 -0.1016)
			(stroke
				(width 0.1)
				(type default)
			)
			(layer "B.Fab")
		)
		(fp_line
			(start 0.3048 -0.1016)
			(end 0.3048 0.9906)
			(stroke
				(width 0.1)
				(type default)
			)
			(layer "B.Fab")
		)
		(fp_line
			(start 0.3048 0.9906)
			(end -0.3048 0.9906)
			(stroke
				(width 0.1)
				(type default)
			)
			(layer "B.Fab")
		)
		(pad "1" smd rect
			(at 0 0 180)
			(size 0.508 0.508)
			(layers "B.Cu" "B.Mask" "B.Paste")
			(net "P3E_CPU0_PE3_OCP_TXP<7>")
		)
		(pad "2" smd rect
			(at 0 0.889 180)
			(size 0.508 0.508)
			(layers "B.Cu" "B.Mask" "B.Paste")
			(net "P3E_OCP_CPU0_PE3_C_TXP<7>")
		)
		(zone
			(layer "B.Cu")
			(hatch none 0.5)
			(connect_pads
				(clearance 0)
			)
			(min_thickness 0.25)
			(keepout
				(tracks allowed)
				(vias not_allowed)
				(pads allowed)
				(copperpour not_allowed)
				(footprints allowed)
			)
			(placement
				(enabled no)
				(sheetname "")
			)
			(fill
				(thermal_gap 0.5)
				(thermal_bridge_width 0.5)
				(island_removal_mode 0)
			)
			(polygon
				(pts
					(xy 440.7154 -52.0446) (xy 440.2074 -52.0446) (xy 440.2074 -51.6636) (xy 440.7154 -51.6636)
				)
			)
		)
		(zone
			(layer "B.Cu")
			(hatch none 0.5)
			(connect_pads
				(clearance 0)
			)
			(min_thickness 0.25)
			(keepout
				(tracks not_allowed)
				(vias allowed)
				(pads allowed)
				(copperpour not_allowed)
				(footprints allowed)
			)
			(placement
				(enabled no)
				(sheetname "")
			)
			(fill
				(thermal_gap 0.5)
				(thermal_bridge_width 0.5)
				(island_removal_mode 0)
			)
			(polygon
				(pts
					(xy 440.7154 -51.6636) (xy 440.2074 -51.6636) (xy 440.2074 -52.0446) (xy 440.7154 -52.0446)
				)
			)
		)
	)
	(footprint ""
		(layer "B.Cu")
		(at 269.902686 -79.60614 180)
		(property "Reference" "C5P13"
			(at 0 0 0)
			(layer "B.SilkS")
			(hide yes)
			(effects
				(font
					(size 1.27 1.27)
				)
				(justify mirror)
			)
		)
		(property "Value" ""
			(at 0 0 0)
			(layer "B.Fab")
			(effects
				(font
					(size 1.27 1.27)
				)
				(justify mirror)
			)
		)
		(duplicate_pad_numbers_are_jumpers no)
		(fp_poly
			(pts
				(xy 0.7239 -0.2159) (xy -0.7239 -0.2159) (xy -0.7239 1.9939) (xy 0.7239 1.9939)
			)
			(stroke
				(width 0)
				(type default)
			)
			(fill no)
			(layer "B.CrtYd")
		)
		(fp_line
			(start 0.7239 1.9939)
			(end -0.7239 1.9939)
			(stroke
				(width 0.1)
				(type default)
			)
			(layer "B.Fab")
		)
		(fp_line
			(start 0.7239 -0.2159)
			(end 0.7239 1.9939)
			(stroke
				(width 0.1)
				(type default)
			)
			(layer "B.Fab")
		)
		(fp_line
			(start -0.7239 1.9939)
			(end -0.7239 -0.2159)
			(stroke
				(width 0.1)
				(type default)
			)
			(layer "B.Fab")
		)
		(fp_line
			(start -0.7239 -0.2159)
			(end 0.7239 -0.2159)
			(stroke
				(width 0.1)
				(type default)
			)
			(layer "B.Fab")
		)
		(pad "1" smd rect
			(at 0 0)
			(size 1.27 1.016)
			(layers "B.Cu" "B.Mask" "B.Paste")
			(net "PVCCMCP_CPU0")
		)
		(pad "2" smd rect
			(at 0 1.778)
			(size 1.27 1.016)
			(layers "B.Cu" "B.Mask" "B.Paste")
			(net "GND")
		)
		(zone
			(layer "B.Cu")
			(hatch none 0.5)
			(connect_pads
				(clearance 0)
			)
			(min_thickness 0.25)
			(keepout
				(tracks not_allowed)
				(vias allowed)
				(pads allowed)
				(copperpour not_allowed)
				(footprints allowed)
			)
			(placement
				(enabled no)
				(sheetname "")
			)
			(fill
				(thermal_gap 0.5)
				(thermal_bridge_width 0.5)
				(island_removal_mode 0)
			)
			(polygon
				(pts
					(xy 269.267686 -80.11414) (xy 270.537686 -80.11414) (xy 270.537686 -80.87614) (xy 269.267686 -80.87614)
				)
			)
		)
	)
)
